(kicad_pcb
	(version 20260206)
	(generator "pcbnew")
	(generator_version "10.0")
	(general
		(thickness 1.6)
		(legacy_teardrops no)
	)
	(paper "A4")
	(title_block
		(title "04192023_DAF0TMB3IC0_F0TG_MB_C_brd_V02_OCP.brd")
		(comment 1 "Grand Teton / footprints 6467-6473 of 8354")
	)
	(layers
		(0 "F.Cu" signal "TOP")
		(4 "In1.Cu" signal "GND")
		(6 "In2.Cu" signal "IN1")
		(8 "In3.Cu" signal "GND1")
		(10 "In4.Cu" signal "IN2")
		(12 "In5.Cu" signal "GND2")
		(14 "In6.Cu" signal "IN3")
		(16 "In7.Cu" signal "GND3")
		(18 "In8.Cu" signal "VCC")
		(20 "In9.Cu" signal "VCC1")
		(22 "In10.Cu" signal "GND4")
		(24 "In11.Cu" signal "IN4")
		(26 "In12.Cu" signal "GND5")
		(28 "In13.Cu" signal "IN5")
		(30 "In14.Cu" signal "GND6")
		(32 "In15.Cu" signal "IN6")
		(34 "In16.Cu" signal "GND7")
		(2 "B.Cu" signal "BOTTOM")
		(9 "F.Adhes" user "F.Adhesive")
		(11 "B.Adhes" user "B.Adhesive")
		(13 "F.Paste" user "Package Geometry/Pastemask Top")
		(15 "B.Paste" user "Package Geometry/Pastemask Bottom")
		(5 "F.SilkS" user "Ref Des/Silkscreen Top")
		(7 "B.SilkS" user "Ref Des/Silkscreen Bottom")
		(1 "F.Mask" user "Board Geometry/Soldermask Top")
		(3 "B.Mask" user "Board Geometry/Soldermask Bottom")
		(17 "Dwgs.User" user "User.Drawings")
		(19 "Cmts.User" user "User.Comments")
		(21 "Eco1.User" user "User.Eco1")
		(23 "Eco2.User" user "User.Eco2")
		(25 "Edge.Cuts" user "Board Geometry/Outline")
		(27 "Margin" user)
		(31 "F.CrtYd" user "Package Geometry/Place Bound Top")
		(29 "B.CrtYd" user "Package Geometry/Place Bound Bottom")
		(35 "F.Fab" user "Ref Des/Assembly Top")
		(33 "B.Fab" user "Ref Des/Assembly Bottom")
	)
	(footprint ""
		(layer "B.Cu")
		(at 300.538388 2.542794)
		(property "Reference" "J119"
			(at 4.387088 1.491742 270)
			(unlocked yes)
			(layer "B.SilkS")
			(effects
				(font
					(size 0.7874 0.5842)
					(thickness 0.1524)
				)
				(justify left mirror)
			)
		)
		(property "Value" ""
			(at 0 0 0)
			(layer "B.Fab")
			(effects
				(font
					(size 1.27 1.27)
				)
				(justify mirror)
			)
		)
		(duplicate_pad_numbers_are_jumpers no)
		(fp_line
			(start -1.2192 -2.06756)
			(end -1.2192 2.06756)
			(stroke
				(width 0.1524)
				(type default)
			)
			(layer "B.SilkS")
		)
		(fp_line
			(start -1.2192 2.06756)
			(end 1.2192 2.06756)
			(stroke
				(width 0.1524)
				(type default)
			)
			(layer "B.SilkS")
		)
		(fp_line
			(start 1.2192 -2.06756)
			(end -1.2192 -2.06756)
			(stroke
				(width 0.1524)
				(type default)
			)
			(layer "B.SilkS")
		)
		(fp_line
			(start 1.2192 2.06756)
			(end 1.2192 -2.06756)
			(stroke
				(width 0.1524)
				(type default)
			)
			(layer "B.SilkS")
		)
		(pad "" np_thru_hole circle
			(at -3.4671 -1.27 270)
			(size 1.0414 1.0414)
			(drill 1.0414)
			(layers "*.Cu" "*.Mask")
			(clearance 0.381)
			(thermal_gap 0.381)
		)
		(pad "" np_thru_hole circle
			(at -3.4671 1.27 270)
			(size 1.0414 1.0414)
			(drill 1.0414)
			(layers "*.Cu" "*.Mask")
			(clearance 0.381)
			(thermal_gap 0.381)
		)
		(pad "" np_thru_hole circle
			(at 2.8829 -1.27 270)
			(size 1.0414 1.0414)
			(drill 1.0414)
			(layers "*.Cu" "*.Mask")
			(clearance 0.381)
			(thermal_gap 0.381)
		)
		(pad "" np_thru_hole circle
			(at 2.8829 1.27 270)
			(size 1.0414 1.0414)
			(drill 1.0414)
			(layers "*.Cu" "*.Mask")
			(clearance 0.381)
			(thermal_gap 0.381)
		)
		(pad "1" smd rect
			(at -0.8255 -0.249936 270)
			(size 0.3048 0.508)
			(layers "B.Cu" "B.Mask" "B.Paste")
			(net "DELTA_L_85_10INCH_IN6_DP")
		)
		(pad "2" smd rect
			(at -0.8255 0.249936 270)
			(size 0.3048 0.508)
			(layers "B.Cu" "B.Mask" "B.Paste")
			(net "DELTA_L_85_10INCH_IN6_DN")
		)
		(pad "3" smd circle
			(at 0 0 180)
			(size 0 0)
			(layers "B.Cu" "B.Mask" "B.Paste")
			(net "DELTA_L_GND_1")
		)
		(zone
			(layers "F.Cu" "B.Cu" "In1.Cu" "In2.Cu" "In3.Cu" "In4.Cu" "In5.Cu" "In6.Cu"
				"In7.Cu" "In8.Cu" "In9.Cu" "In10.Cu" "In11.Cu" "In12.Cu" "In13.Cu" "In14.Cu"
				"In15.Cu" "In16.Cu"
			)
			(hatch none 0.5)
			(connect_pads
				(clearance 0)
			)
			(min_thickness 0.25)
			(keepout
				(tracks not_allowed)
				(vias allowed)
				(pads allowed)
				(copperpour not_allowed)
				(footprints allowed)
			)
			(placement
				(enabled no)
				(sheetname "")
			)
			(fill
				(thermal_gap 0.5)
				(thermal_bridge_width 0.5)
				(island_removal_mode 0)
			)
			(polygon
				(pts
					(arc
						(start 297.998388 1.272794)
						(mid 296.144188 1.272794)
						(end 297.998388 1.272794)
					)
				)
			)
		)
		(zone
			(layers "F.Cu" "B.Cu" "In1.Cu" "In2.Cu" "In3.Cu" "In4.Cu" "In5.Cu" "In6.Cu"
				"In7.Cu" "In8.Cu" "In9.Cu" "In10.Cu" "In11.Cu" "In12.Cu" "In13.Cu" "In14.Cu"
				"In15.Cu" "In16.Cu"
			)
			(hatch none 0.5)
			(connect_pads
				(clearance 0)
			)
			(min_thickness 0.25)
			(keepout
				(tracks not_allowed)
				(vias allowed)
				(pads allowed)
				(copperpour not_allowed)
				(footprints allowed)
			)
			(placement
				(enabled no)
				(sheetname "")
			)
			(fill
				(thermal_gap 0.5)
				(thermal_bridge_width 0.5)
				(island_removal_mode 0)
			)
			(polygon
				(pts
					(arc
						(start 297.998388 3.812794)
						(mid 296.144188 3.812794)
						(end 297.998388 3.812794)
					)
				)
			)
		)
		(zone
			(layers "F.Cu" "B.Cu" "In1.Cu" "In2.Cu" "In3.Cu" "In4.Cu" "In5.Cu" "In6.Cu"
				"In7.Cu" "In8.Cu" "In9.Cu" "In10.Cu" "In11.Cu" "In12.Cu" "In13.Cu" "In14.Cu"
				"In15.Cu" "In16.Cu"
			)
			(hatch none 0.5)
			(connect_pads
				(clearance 0)
			)
			(min_thickness 0.25)
			(keepout
				(tracks not_allowed)
				(vias allowed)
				(pads allowed)
				(copperpour not_allowed)
				(footprints allowed)
			)
			(placement
				(enabled no)
				(sheetname "")
			)
			(fill
				(thermal_gap 0.5)
				(thermal_bridge_width 0.5)
				(island_removal_mode 0)
			)
			(polygon
				(pts
					(arc
						(start 304.348388 1.272794)
						(mid 302.494188 1.272794)
						(end 304.348388 1.272794)
					)
				)
			)
		)
		(zone
			(layers "F.Cu" "B.Cu" "In1.Cu" "In2.Cu" "In3.Cu" "In4.Cu" "In5.Cu" "In6.Cu"
				"In7.Cu" "In8.Cu" "In9.Cu" "In10.Cu" "In11.Cu" "In12.Cu" "In13.Cu" "In14.Cu"
				"In15.Cu" "In16.Cu"
			)
			(hatch none 0.5)
			(connect_pads
				(clearance 0)
			)
			(min_thickness 0.25)
			(keepout
				(tracks not_allowed)
				(vias allowed)
				(pads allowed)
				(copperpour not_allowed)
				(footprints allowed)
			)
			(placement
				(enabled no)
				(sheetname "")
			)
			(fill
				(thermal_gap 0.5)
				(thermal_bridge_width 0.5)
				(island_removal_mode 0)
			)
			(polygon
				(pts
					(arc
						(start 304.348388 3.812794)
						(mid 302.494188 3.812794)
						(end 304.348388 3.812794)
					)
				)
			)
		)
		(zone
			(layer "B.Cu")
			(hatch none 0.5)
			(connect_pads
				(clearance 0)
			)
			(min_thickness 0.25)
			(keepout
				(tracks not_allowed)
				(vias allowed)
				(pads allowed)
				(copperpour not_allowed)
				(footprints allowed)
			)
			(placement
				(enabled no)
				(sheetname "")
			)
			(fill
				(thermal_gap 0.5)
				(thermal_bridge_width 0.5)
				(island_removal_mode 0)
			)
			(polygon
				(pts
					(xy 299.420788 1.994154) (xy 299.420788 2.089658) (xy 300.017688 2.089658) (xy 300.017688 2.496058)
					(xy 299.420788 2.496058) (xy 299.420788 2.58953) (xy 300.017688 2.58953) (xy 300.017688 2.99593)
					(xy 299.420788 2.99593) (xy 299.420788 3.091434) (xy 300.119288 3.091434) (xy 300.119288 1.994154)
				)
			)
		)
	)
	(footprint ""
		(layer "B.Cu")
		(at 110.365794 -383.7432 180)
		(property "Reference" "R910"
			(at 0 0 0)
			(layer "B.SilkS")
			(hide yes)
			(effects
				(font
					(size 1.27 1.27)
				)
				(justify mirror)
			)
		)
		(property "Value" ""
			(at 0 0 0)
			(layer "B.Fab")
			(effects
				(font
					(size 1.27 1.27)
				)
				(justify mirror)
			)
		)
		(duplicate_pad_numbers_are_jumpers no)
		(fp_line
			(start 0.32512 0.175006)
			(end 0.32512 -0.175006)
			(stroke
				(width 0.1)
				(type default)
			)
			(layer "B.Fab")
		)
		(fp_line
			(start 0.32512 -0.175006)
			(end -0.32512 -0.175006)
			(stroke
				(width 0.1)
				(type default)
			)
			(layer "B.Fab")
		)
		(fp_line
			(start -0.32512 0.175006)
			(end 0.32512 0.175006)
			(stroke
				(width 0.1)
				(type default)
			)
			(layer "B.Fab")
		)
		(fp_line
			(start -0.32512 -0.175006)
			(end -0.32512 0.175006)
			(stroke
				(width 0.1)
				(type default)
			)
			(layer "B.Fab")
		)
		(pad "1" smd rect
			(at 0.2667 0)
			(size 0.3048 0.381)
			(layers "B.Cu" "B.Mask" "B.Paste")
			(net "RT_CPU1_P3_SCAN_MODE")
		)
		(pad "2" smd rect
			(at -0.2667 0 180)
			(size 0.3048 0.381)
			(layers "B.Cu" "B.Mask" "B.Paste")
			(net "GND")
		)
	)
	(footprint ""
		(layer "B.Cu")
		(at 191.196214 -344.177112 -90)
		(property "Reference" "PC528"
			(at 7.567676 -4.797806 270)
			(unlocked yes)
			(layer "B.SilkS")
			(effects
				(font
					(size 0.7874 0.5842)
					(thickness 0.1524)
				)
				(justify left mirror)
			)
		)
		(property "Value" ""
			(at 0 0 90)
			(layer "B.Fab")
			(effects
				(font
					(size 1.27 1.27)
				)
				(justify mirror)
			)
		)
		(duplicate_pad_numbers_are_jumpers no)
		(fp_line
			(start -4.533392 2.249932)
			(end 4.533392 2.249932)
			(stroke
				(width 0.1524)
				(type default)
			)
			(layer "B.SilkS")
		)
		(fp_line
			(start 4.533392 2.249932)
			(end 4.533392 -2.249932)
			(stroke
				(width 0.1524)
				(type default)
			)
			(layer "B.SilkS")
		)
		(fp_line
			(start -4.533392 -2.249932)
			(end -4.533392 2.249932)
			(stroke
				(width 0.1524)
				(type default)
			)
			(layer "B.SilkS")
		)
		(fp_line
			(start 4.533392 -2.249932)
			(end -4.533392 -2.249932)
			(stroke
				(width 0.1524)
				(type default)
			)
			(layer "B.SilkS")
		)
		(fp_rect
			(start 5.39242 2.326132)
			(end 4.533392 -2.326132)
			(stroke
				(width 0)
				(type default)
			)
			(fill yes)
			(layer "B.SilkS")
		)
		(fp_line
			(start -3.750056 2.249932)
			(end 3.750056 2.249932)
			(stroke
				(width 0.1)
				(type default)
			)
			(layer "B.Fab")
		)
		(fp_line
			(start 3.750056 2.249932)
			(end 3.750056 -2.249932)
			(stroke
				(width 0.1)
				(type default)
			)
			(layer "B.Fab")
		)
		(fp_line
			(start -3.750056 -2.249932)
			(end -3.750056 2.249932)
			(stroke
				(width 0.1)
				(type default)
			)
			(layer "B.Fab")
		)
		(fp_line
			(start 3.750056 -2.249932)
			(end -3.750056 -2.249932)
			(stroke
				(width 0.1)
				(type default)
			)
			(layer "B.Fab")
		)
		(fp_text user "-"
			(at -4.956048 2.39776 270)
			(unlocked yes)
			(layer "B.SilkS")
			(effects
				(font
					(size 1.905 1.4224)
					(thickness 0.1524)
				)
				(justify left mirror)
			)
		)
		(fp_text user "+"
			(at 6.322314 0.786384 180)
			(unlocked yes)
			(layer "B.SilkS")
			(effects
				(font
					(size 1.905 1.4224)
					(thickness 0.1524)
				)
				(justify left mirror)
			)
		)
		(fp_text user "+"
			(at 6.322314 0.786384 180)
			(unlocked yes)
			(layer "B.Fab")
			(effects
				(font
					(size 1.905 1.4224)
					(thickness 0.1524)
				)
				(justify left mirror)
			)
		)
		(fp_text user "-"
			(at -4.8514 -0.14605 270)
			(unlocked yes)
			(layer "B.Fab")
			(effects
				(font
					(size 1.905 1.4224)
					(thickness 0.1524)
				)
				(justify left mirror)
			)
		)
		(pad "1" smd rect
			(at 3.199892 0 90)
			(size 2.413 2.8194)
			(layers "B.Cu" "B.Mask" "B.Paste")
			(net "PVDD11_S3_P1")
		)
		(pad "2" smd rect
			(at -3.199892 0 90)
			(size 2.413 2.8194)
			(layers "B.Cu" "B.Mask" "B.Paste")
			(net "GND")
		)
	)
	(footprint ""
		(layer "B.Cu")
		(at 373.314722 -416.899344 90)
		(property "Reference" "C6597"
			(at 0 0 90)
			(layer "B.SilkS")
			(hide yes)
			(effects
				(font
					(size 1.27 1.27)
				)
				(justify mirror)
			)
		)
		(property "Value" ""
			(at 0 0 90)
			(layer "B.Fab")
			(effects
				(font
					(size 1.27 1.27)
				)
				(justify mirror)
			)
		)
		(duplicate_pad_numbers_are_jumpers no)
		(fp_line
			(start 0.299974 -0.150114)
			(end -0.299974 -0.150114)
			(stroke
				(width 0.1)
				(type default)
			)
			(layer "B.Fab")
		)
		(fp_line
			(start -0.299974 -0.150114)
			(end -0.299974 0.150114)
			(stroke
				(width 0.1)
				(type default)
			)
			(layer "B.Fab")
		)
		(fp_line
			(start 0.299974 0.150114)
			(end 0.299974 -0.150114)
			(stroke
				(width 0.1)
				(type default)
			)
			(layer "B.Fab")
		)
		(fp_line
			(start -0.299974 0.150114)
			(end 0.299974 0.150114)
			(stroke
				(width 0.1)
				(type default)
			)
			(layer "B.Fab")
		)
		(pad "1" smd rect
			(at 0.2667 0 270)
			(size 0.3048 0.381)
			(layers "B.Cu" "B.Mask" "B.Paste")
			(net "P5E_CPU0_P3_TX_BUF_C_DP<0>")
		)
		(pad "2" smd rect
			(at -0.2667 0 270)
			(size 0.3048 0.381)
			(layers "B.Cu" "B.Mask" "B.Paste")
			(net "P5E_CPU0_P3_TX_BUF_DP<0>")
		)
	)
	(footprint ""
		(layer "B.Cu")
		(at 122.526806 -408.517344 90)
		(property "Reference" "C6730"
			(at 0 0 90)
			(layer "B.SilkS")
			(hide yes)
			(effects
				(font
					(size 1.27 1.27)
				)
				(justify mirror)
			)
		)
		(property "Value" ""
			(at 0 0 90)
			(layer "B.Fab")
			(effects
				(font
					(size 1.27 1.27)
				)
				(justify mirror)
			)
		)
		(duplicate_pad_numbers_are_jumpers no)
		(fp_line
			(start 0.299974 -0.150114)
			(end -0.299974 -0.150114)
			(stroke
				(width 0.1)
				(type default)
			)
			(layer "B.Fab")
		)
		(fp_line
			(start -0.299974 -0.150114)
			(end -0.299974 0.150114)
			(stroke
				(width 0.1)
				(type default)
			)
			(layer "B.Fab")
		)
		(fp_line
			(start 0.299974 0.150114)
			(end 0.299974 -0.150114)
			(stroke
				(width 0.1)
				(type default)
			)
			(layer "B.Fab")
		)
		(fp_line
			(start -0.299974 0.150114)
			(end 0.299974 0.150114)
			(stroke
				(width 0.1)
				(type default)
			)
			(layer "B.Fab")
		)
		(pad "1" smd rect
			(at 0.2667 0 270)
			(size 0.3048 0.381)
			(layers "B.Cu" "B.Mask" "B.Paste")
			(net "P5E_CPU1_P3_TX_BUF_C_DN<2>")
		)
		(pad "2" smd rect
			(at -0.2667 0 270)
			(size 0.3048 0.381)
			(layers "B.Cu" "B.Mask" "B.Paste")
			(net "P5E_CPU1_P3_TX_BUF_DN<2>")
		)
	)
	(footprint ""
		(layer "B.Cu")
		(at 130.104642 -78.52918)
		(property "Reference" "PC6025"
			(at 0 0 0)
			(layer "B.SilkS")
			(hide yes)
			(effects
				(font
					(size 1.27 1.27)
				)
				(justify mirror)
			)
		)
		(property "Value" ""
			(at 0 0 0)
			(layer "B.Fab")
			(effects
				(font
					(size 1.27 1.27)
				)
				(justify mirror)
			)
		)
		(duplicate_pad_numbers_are_jumpers no)
		(fp_line
			(start -1.524 -0.762)
			(end -1.524 0.762)
			(stroke
				(width 0.1524)
				(type default)
			)
			(layer "B.SilkS")
		)
		(fp_line
			(start -1.524 0.762)
			(end 1.524 0.762)
			(stroke
				(width 0.1524)
				(type default)
			)
			(layer "B.SilkS")
		)
		(fp_line
			(start 1.524 -0.762)
			(end -1.524 -0.762)
			(stroke
				(width 0.1524)
				(type default)
			)
			(layer "B.SilkS")
		)
		(fp_line
			(start 1.524 0.762)
			(end 1.524 -0.762)
			(stroke
				(width 0.1524)
				(type default)
			)
			(layer "B.SilkS")
		)
		(fp_line
			(start -1.1049 -0.724916)
			(end 1.1049 -0.724916)
			(stroke
				(width 0.1)
				(type default)
			)
			(layer "B.Fab")
		)
		(fp_line
			(start -1.1049 0.724916)
			(end -1.1049 -0.724916)
			(stroke
				(width 0.1)
				(type default)
			)
			(layer "B.Fab")
		)
		(fp_line
			(start 1.1049 -0.724916)
			(end 1.1049 0.724916)
			(stroke
				(width 0.1)
				(type default)
			)
			(layer "B.Fab")
		)
		(fp_line
			(start 1.1049 0.724916)
			(end -1.1049 0.724916)
			(stroke
				(width 0.1)
				(type default)
			)
			(layer "B.Fab")
		)
		(pad "1" smd rect
			(at 0.889 0)
			(size 1.016 1.27)
			(layers "B.Cu" "B.Mask" "B.Paste")
			(net "P1V2_AUX")
		)
		(pad "2" smd rect
			(at -0.889 0)
			(size 1.016 1.27)
			(layers "B.Cu" "B.Mask" "B.Paste")
			(net "GND")
		)
	)
	(footprint ""
		(layer "B.Cu")
		(at 338.186522 -326.341232 -90)
		(property "Reference" "PC102_1"
			(at 0 0 90)
			(layer "B.SilkS")
			(hide yes)
			(effects
				(font
					(size 1.27 1.27)
				)
				(justify mirror)
			)
		)
		(property "Value" ""
			(at 0 0 90)
			(layer "B.Fab")
			(effects
				(font
					(size 1.27 1.27)
				)
				(justify mirror)
			)
		)
		(duplicate_pad_numbers_are_jumpers no)
		(fp_line
			(start -1.524 0.762)
			(end 1.524 0.762)
			(stroke
				(width 0.1524)
				(type default)
			)
			(layer "B.SilkS")
		)
		(fp_line
			(start 1.524 0.762)
			(end 1.524 -0.762)
			(stroke
				(width 0.1524)
				(type default)
			)
			(layer "B.SilkS")
		)
		(fp_line
			(start -1.524 -0.762)
			(end -1.524 0.762)
			(stroke
				(width 0.1524)
				(type default)
			)
			(layer "B.SilkS")
		)
		(fp_line
			(start 1.524 -0.762)
			(end -1.524 -0.762)
			(stroke
				(width 0.1524)
				(type default)
			)
			(layer "B.SilkS")
		)
		(fp_line
			(start -1.1049 0.724916)
			(end -1.1049 -0.724916)
			(stroke
				(width 0.1)
				(type default)
			)
			(layer "B.Fab")
		)
		(fp_line
			(start 1.1049 0.724916)
			(end -1.1049 0.724916)
			(stroke
				(width 0.1)
				(type default)
			)
			(layer "B.Fab")
		)
		(fp_line
			(start -1.1049 -0.724916)
			(end 1.1049 -0.724916)
			(stroke
				(width 0.1)
				(type default)
			)
			(layer "B.Fab")
		)
		(fp_line
			(start 1.1049 -0.724916)
			(end 1.1049 0.724916)
			(stroke
				(width 0.1)
				(type default)
			)
			(layer "B.Fab")
		)
		(pad "1" smd rect
			(at 0.889 0 270)
			(size 1.016 1.27)
			(layers "B.Cu" "B.Mask" "B.Paste")
			(net "PVDDCR_CPU1_P0")
		)
		(pad "2" smd rect
			(at -0.889 0 270)
			(size 1.016 1.27)
			(layers "B.Cu" "B.Mask" "B.Paste")
			(net "GND")
		)
	)
)
